# BASEBOARD_FAB2 (Tioga Pass) — schematic netlist excerpt (pin names and nets, part order shuffled) for the footprints in the layout excerpt that follows; sources: Cadence DE-HDL packaged netlist, KiCad conversion of Wiwynn_Tioga_Pass_MB.brd

R1R9  RES  3.32K 1% CHIP  pkg 0402  page 140 : A = P3V3_STBY ; B = PU_NV_HOLD_N
C5U9  CAP_A  47UF 4V 20% X5R  pkg 0603V  page 217 : A = PVDDQ_ABC ; B = GND
R12W11  665KR5B-1-GP  0.1%  pkg SMD-RG3  page 197 : \1\ = P12V_STBY ; \2\ = VR_PVDDQ_GHJ_AIINSEN

(kicad_pcb
	(version 20260206)
	(generator "pcbnew")
	(generator_version "10.0")
	(general
		(thickness 1.6)
		(legacy_teardrops no)
	)
	(paper "A4")
	(title_block
		(title "Wiwynn_Tioga_Pass_MB.brd")
		(comment 1 "Tioga Pass / footprints 3159-3161 of 4770")
	)
	(layers
		(0 "F.Cu" signal "TOP")
		(4 "In1.Cu" signal "L2GND")
		(6 "In2.Cu" signal "L3")
		(8 "In3.Cu" signal "L4GND")
		(10 "In4.Cu" signal "L5")
		(12 "In5.Cu" signal "L6GND")
		(14 "In6.Cu" signal "L7VCC")
		(16 "In7.Cu" signal "L8VCC")
		(18 "In8.Cu" signal "L9GND")
		(20 "In9.Cu" signal "L10")
		(22 "In10.Cu" signal "L11GND")
		(24 "In11.Cu" signal "L12")
		(26 "In12.Cu" signal "L13GND")
		(2 "B.Cu" signal "BOTTOM")
		(9 "F.Adhes" user "F.Adhesive")
		(11 "B.Adhes" user "B.Adhesive")
		(13 "F.Paste" user "Package Geometry/Pastemask Top")
		(15 "B.Paste" user "Package Geometry/Pastemask Bottom")
		(5 "F.SilkS" user "Ref Des/Silkscreen Top")
		(7 "B.SilkS" user "Ref Des/Silkscreen Bottom")
		(1 "F.Mask" user "Board Geometry/Soldermask Top")
		(3 "B.Mask" user "Board Geometry/Soldermask Bottom")
		(17 "Dwgs.User" user "User.Drawings")
		(19 "Cmts.User" user "User.Comments")
		(21 "Eco1.User" user "User.Eco1")
		(23 "Eco2.User" user "User.Eco2")
		(25 "Edge.Cuts" user "Board Geometry/Outline")
		(27 "Margin" user)
		(31 "F.CrtYd" user "Package Geometry/Place Bound Top")
		(29 "B.CrtYd" user "Package Geometry/Place Bound Bottom")
		(35 "F.Fab" user "Ref Des/Assembly Top")
		(33 "B.Fab" user "Ref Des/Assembly Bottom")
	)
	(footprint ""
		(layer "B.Cu")
		(at 488.98429 -29.3116)
		(property "Reference" "R1R9"
			(at 0.8382 -0.67818 0)
			(unlocked yes)
			(layer "B.SilkS")
			(effects
				(font
					(size 0.4064 0.254)
					(thickness 0.1524)
				)
				(justify left mirror)
			)
		)
		(property "Value" ""
			(at 0 0 0)
			(layer "B.Fab")
			(effects
				(font
					(size 1.27 1.27)
				)
				(justify mirror)
			)
		)
		(duplicate_pad_numbers_are_jumpers no)
		(fp_poly
			(pts
				(xy 0.2794 -0.1016) (xy -0.2794 -0.1016) (xy -0.2794 0.9906) (xy 0.2794 0.9906)
			)
			(stroke
				(width 0)
				(type default)
			)
			(fill no)
			(layer "B.CrtYd")
		)
		(fp_line
			(start -0.2794 -0.1016)
			(end 0.2794 -0.1016)
			(stroke
				(width 0.1)
				(type default)
			)
			(layer "B.Fab")
		)
		(fp_line
			(start -0.2794 0.9906)
			(end -0.2794 -0.1016)
			(stroke
				(width 0.1)
				(type default)
			)
			(layer "B.Fab")
		)
		(fp_line
			(start 0.2794 -0.1016)
			(end 0.2794 0.9906)
			(stroke
				(width 0.1)
				(type default)
			)
			(layer "B.Fab")
		)
		(fp_line
			(start 0.2794 0.9906)
			(end -0.2794 0.9906)
			(stroke
				(width 0.1)
				(type default)
			)
			(layer "B.Fab")
		)
		(pad "1" smd rect
			(at 0 0 180)
			(size 0.508 0.508)
			(layers "B.Cu" "B.Mask" "B.Paste")
			(net "P3V3_STBY")
		)
		(pad "2" smd rect
			(at 0 0.889 180)
			(size 0.508 0.508)
			(layers "B.Cu" "B.Mask" "B.Paste")
			(net "PU_NV_HOLD_N")
		)
		(zone
			(layer "B.Cu")
			(hatch none 0.5)
			(connect_pads
				(clearance 0)
			)
			(min_thickness 0.25)
			(keepout
				(tracks allowed)
				(vias not_allowed)
				(pads allowed)
				(copperpour not_allowed)
				(footprints allowed)
			)
			(placement
				(enabled no)
				(sheetname "")
			)
			(fill
				(thermal_gap 0.5)
				(thermal_bridge_width 0.5)
				(island_removal_mode 0)
			)
			(polygon
				(pts
					(xy 489.23829 -29.0576) (xy 488.73029 -29.0576) (xy 488.73029 -28.6766) (xy 489.23829 -28.6766)
				)
			)
		)
		(zone
			(layer "B.Cu")
			(hatch none 0.5)
			(connect_pads
				(clearance 0)
			)
			(min_thickness 0.25)
			(keepout
				(tracks not_allowed)
				(vias allowed)
				(pads allowed)
				(copperpour not_allowed)
				(footprints allowed)
			)
			(placement
				(enabled no)
				(sheetname "")
			)
			(fill
				(thermal_gap 0.5)
				(thermal_bridge_width 0.5)
				(island_removal_mode 0)
			)
			(polygon
				(pts
					(xy 489.23829 -28.6766) (xy 488.73029 -28.6766) (xy 488.73029 -29.0576) (xy 489.23829 -29.0576)
				)
			)
		)
	)
	(footprint ""
		(layer "B.Cu")
		(at 245.7577 -8.1534 -90)
		(property "Reference" "C5U9"
			(at -1.848866 0.752348 270)
			(unlocked yes)
			(layer "B.SilkS")
			(effects
				(font
					(size 1.27 0.9652)
					(thickness 0.1524)
				)
				(justify mirror)
			)
		)
		(property "Value" ""
			(at 0 0 90)
			(layer "B.Fab")
			(effects
				(font
					(size 1.27 1.27)
				)
				(justify mirror)
			)
		)
		(duplicate_pad_numbers_are_jumpers no)
		(fp_rect
			(start 0.500126 1.598422)
			(end -0.500126 -0.201422)
			(stroke
				(width 0)
				(type default)
			)
			(fill no)
			(layer "B.CrtYd")
		)
		(fp_line
			(start -0.500126 1.598422)
			(end 0.500126 1.598422)
			(stroke
				(width 0.1)
				(type default)
			)
			(layer "B.Fab")
		)
		(fp_line
			(start 0.500126 1.598422)
			(end 0.500126 -0.201422)
			(stroke
				(width 0.1)
				(type default)
			)
			(layer "B.Fab")
		)
		(fp_line
			(start -0.500126 -0.201422)
			(end -0.500126 1.598422)
			(stroke
				(width 0.1)
				(type default)
			)
			(layer "B.Fab")
		)
		(fp_line
			(start 0.500126 -0.201422)
			(end -0.500126 -0.201422)
			(stroke
				(width 0.1)
				(type default)
			)
			(layer "B.Fab")
		)
		(pad "1" smd rect
			(at 0 0 180)
			(size 0.889 0.9906)
			(layers "B.Cu" "B.Mask" "B.Paste")
			(net "PVDDQ_ABC")
		)
		(pad "2" smd rect
			(at 0 1.397 180)
			(size 0.889 0.9906)
			(layers "B.Cu" "B.Mask" "B.Paste")
			(net "GND")
		)
		(zone
			(layer "B.Cu")
			(hatch none 0.5)
			(connect_pads
				(clearance 0)
			)
			(min_thickness 0.25)
			(keepout
				(tracks not_allowed)
				(vias allowed)
				(pads allowed)
				(copperpour not_allowed)
				(footprints allowed)
			)
			(placement
				(enabled no)
				(sheetname "")
			)
			(fill
				(thermal_gap 0.5)
				(thermal_bridge_width 0.5)
				(island_removal_mode 0)
			)
			(polygon
				(pts
					(xy 244.8052 -7.6581) (xy 245.3132 -7.6581) (xy 245.3132 -8.6487) (xy 244.8052 -8.6487)
				)
			)
		)
		(zone
			(layer "B.Cu")
			(hatch none 0.5)
			(connect_pads
				(clearance 0)
			)
			(min_thickness 0.25)
			(keepout
				(tracks allowed)
				(vias not_allowed)
				(pads allowed)
				(copperpour not_allowed)
				(footprints allowed)
			)
			(placement
				(enabled no)
				(sheetname "")
			)
			(fill
				(thermal_gap 0.5)
				(thermal_bridge_width 0.5)
				(island_removal_mode 0)
			)
			(polygon
				(pts
					(xy 244.8052 -7.6581) (xy 245.3132 -7.6581) (xy 245.3132 -8.6487) (xy 244.8052 -8.6487)
				)
			)
		)
	)
	(footprint ""
		(layer "B.Cu")
		(at 11.881358 3.20802)
		(property "Reference" "R12W11"
			(at 0 0 0)
			(layer "B.SilkS")
			(hide yes)
			(effects
				(font
					(size 1.27 1.27)
				)
				(justify mirror)
			)
		)
		(property "Value" "*"
			(at 0 -8.9535 0)
			(unlocked yes)
			(layer "B.Fab")
			(hide yes)
			(effects
				(font
					(size 1.27 1.016)
					(thickness 0.1524)
				)
				(justify mirror)
			)
		)
		(property "Device Type" "665KR5B-1-GP_SMD-RG3-665KR5B-1A"
			(at 0 -10.6299 0)
			(unlocked yes)
			(layer "B.Fab")
			(hide yes)
			(effects
				(font
					(size 1.27 1.016)
					(thickness 0.1524)
				)
				(justify mirror)
			)
		)
		(duplicate_pad_numbers_are_jumpers no)
		(fp_line
			(start -0.889 -1.7018)
			(end -0.889 -0.381)
			(stroke
				(width 0.1524)
				(type default)
			)
			(layer "B.SilkS")
		)
		(fp_line
			(start -0.889 -1.7018)
			(end 0.889 -1.7018)
			(stroke
				(width 0.1524)
				(type default)
			)
			(layer "B.SilkS")
		)
		(fp_line
			(start -0.889 1.7018)
			(end -0.889 -0.508)
			(stroke
				(width 0.1524)
				(type default)
			)
			(layer "B.SilkS")
		)
		(fp_line
			(start 0.889 -1.7018)
			(end 0.889 0.2794)
			(stroke
				(width 0.1524)
				(type default)
			)
			(layer "B.SilkS")
		)
		(fp_line
			(start 0.889 0.0762)
			(end 0.889 1.7018)
			(stroke
				(width 0.1524)
				(type default)
			)
			(layer "B.SilkS")
		)
		(fp_line
			(start 0.889 1.7018)
			(end -0.889 1.7018)
			(stroke
				(width 0.1524)
				(type default)
			)
			(layer "B.SilkS")
		)
		(fp_poly
			(pts
				(xy -0.9652 -1.778) (xy -0.9652 1.778) (xy 0.9652 1.778) (xy 0.9652 -1.778)
			)
			(stroke
				(width 0)
				(type default)
			)
			(fill no)
			(layer "B.CrtYd")
		)
		(fp_rect
			(start 0.9652 1.778)
			(end -0.9652 -1.778)
			(stroke
				(width 0)
				(type default)
			)
			(fill no)
			(layer "B.Fab")
		)
		(pad "1" smd rect
			(at 0 -0.9652 180)
			(size 1.397 1.143)
			(layers "B.Cu" "B.Mask" "B.Paste")
			(net "P12V_STBY")
		)
		(pad "2" smd rect
			(at 0 0.9652 180)
			(size 1.397 1.143)
			(layers "B.Cu" "B.Mask" "B.Paste")
			(net "VR_PVDDQ_GHJ_AIINSEN")
		)
	)
)
